(kicad_pcb
	(version 20260206)
	(generator "pcbnew")
	(generator_version "10.0")
	(general
		(thickness 1.6)
		(legacy_teardrops no)
	)
	(paper "A4")
	(title_block
		(title "01162023_DA0F0TEBIF0_F0T_Expander_BD_F_brd_V02_OCP.brd")
		(comment 1 "Grand Teton / footprints 5112-5117 of 9728")
	)
	(layers
		(0 "F.Cu" signal "TOP")
		(4 "In1.Cu" signal "GND")
		(6 "In2.Cu" signal "VCC")
		(8 "In3.Cu" signal "VCC1")
		(10 "In4.Cu" signal "GND1")
		(12 "In5.Cu" signal "IN1")
		(14 "In6.Cu" signal "GND2")
		(16 "In7.Cu" signal "IN2")
		(18 "In8.Cu" signal "GND3")
		(20 "In9.Cu" signal "IN3")
		(22 "In10.Cu" signal "GND4")
		(24 "In11.Cu" signal "IN4")
		(26 "In12.Cu" signal "GND5")
		(28 "In13.Cu" signal "IN5")
		(30 "In14.Cu" signal "GND6")
		(32 "In15.Cu" signal "IN6")
		(34 "In16.Cu" signal "GND7")
		(2 "B.Cu" signal "BOTTOM")
		(9 "F.Adhes" user "F.Adhesive")
		(11 "B.Adhes" user "B.Adhesive")
		(13 "F.Paste" user "Package Geometry/Pastemask Top")
		(15 "B.Paste" user "Package Geometry/Pastemask Bottom")
		(5 "F.SilkS" user "Ref Des/Silkscreen Top")
		(7 "B.SilkS" user "Ref Des/Silkscreen Bottom")
		(1 "F.Mask" user "Board Geometry/Soldermask Top")
		(3 "B.Mask" user "Board Geometry/Soldermask Bottom")
		(17 "Dwgs.User" user "User.Drawings")
		(19 "Cmts.User" user "User.Comments")
		(21 "Eco1.User" user "User.Eco1")
		(23 "Eco2.User" user "User.Eco2")
		(25 "Edge.Cuts" user "Board Geometry/Outline")
		(27 "Margin" user)
		(31 "F.CrtYd" user "Package Geometry/Place Bound Top")
		(29 "B.CrtYd" user "Package Geometry/Place Bound Bottom")
		(35 "F.Fab" user "Ref Des/Assembly Top")
		(33 "B.Fab" user "Ref Des/Assembly Bottom")
	)
	(footprint ""
		(layer "F.Cu")
		(at 47.885604 -27.092148 -90)
		(property "Reference" "R5733"
			(at 0 0 270)
			(layer "F.SilkS")
			(hide yes)
			(effects
				(font
					(size 1.27 1.27)
				)
			)
		)
		(property "Value" ""
			(at 0 0 270)
			(layer "F.Fab")
			(effects
				(font
					(size 1.27 1.27)
				)
			)
		)
		(duplicate_pad_numbers_are_jumpers no)
		(fp_line
			(start -0.7874 0.4064)
			(end -0.7874 -0.4064)
			(stroke
				(width 0.1524)
				(type default)
			)
			(layer "F.SilkS")
		)
		(fp_line
			(start 0.7874 0.4064)
			(end -0.7874 0.4064)
			(stroke
				(width 0.1524)
				(type default)
			)
			(layer "F.SilkS")
		)
		(fp_line
			(start -0.7874 -0.4064)
			(end 0.7874 -0.4064)
			(stroke
				(width 0.1524)
				(type default)
			)
			(layer "F.SilkS")
		)
		(fp_line
			(start 0.7874 -0.4064)
			(end 0.7874 0.4064)
			(stroke
				(width 0.1524)
				(type default)
			)
			(layer "F.SilkS")
		)
		(fp_line
			(start -0.67945 0.3048)
			(end -0.67945 -0.305054)
			(stroke
				(width 0.1)
				(type default)
			)
			(layer "F.Fab")
		)
		(fp_line
			(start -0.12065 0.3048)
			(end -0.67945 0.3048)
			(stroke
				(width 0.1)
				(type default)
			)
			(layer "F.Fab")
		)
		(fp_line
			(start 0.120396 0.3048)
			(end 0.120396 0.2794)
			(stroke
				(width 0.1)
				(type default)
			)
			(layer "F.Fab")
		)
		(fp_line
			(start 0.67945 0.3048)
			(end 0.120396 0.3048)
			(stroke
				(width 0.1)
				(type default)
			)
			(layer "F.Fab")
		)
		(fp_line
			(start -0.12065 0.2794)
			(end -0.12065 0.3048)
			(stroke
				(width 0.1)
				(type default)
			)
			(layer "F.Fab")
		)
		(fp_line
			(start 0.120396 0.2794)
			(end -0.12065 0.2794)
			(stroke
				(width 0.1)
				(type default)
			)
			(layer "F.Fab")
		)
		(fp_line
			(start -0.12065 -0.2794)
			(end 0.12065 -0.2794)
			(stroke
				(width 0.1)
				(type default)
			)
			(layer "F.Fab")
		)
		(fp_line
			(start 0.12065 -0.2794)
			(end 0.12065 -0.3048)
			(stroke
				(width 0.1)
				(type default)
			)
			(layer "F.Fab")
		)
		(fp_line
			(start 0.12065 -0.3048)
			(end 0.67945 -0.3048)
			(stroke
				(width 0.1)
				(type default)
			)
			(layer "F.Fab")
		)
		(fp_line
			(start 0.67945 -0.3048)
			(end 0.67945 0.3048)
			(stroke
				(width 0.1)
				(type default)
			)
			(layer "F.Fab")
		)
		(fp_line
			(start -0.67945 -0.305054)
			(end -0.12065 -0.305054)
			(stroke
				(width 0.1)
				(type default)
			)
			(layer "F.Fab")
		)
		(fp_line
			(start -0.12065 -0.305054)
			(end -0.12065 -0.2794)
			(stroke
				(width 0.1)
				(type default)
			)
			(layer "F.Fab")
		)
		(pad "1" smd circle
			(at -0.40005 0 270)
			(size 0 0)
			(layers "F.Cu" "F.Mask" "F.Paste")
			(net "P3V3_SSD1")
		)
		(pad "2" smd circle
			(at 0.40005 0 270)
			(size 0 0)
			(layers "F.Cu" "F.Mask" "F.Paste")
			(net "SSD1_LED_ISO_N")
		)
	)
	(footprint ""
		(layer "F.Cu")
		(at 30.261814 -311.007252 -135)
		(property "Reference" "R1257"
			(at 0 0 225)
			(layer "F.SilkS")
			(hide yes)
			(effects
				(font
					(size 1.27 1.27)
				)
			)
		)
		(property "Value" ""
			(at 0 0 225)
			(layer "F.Fab")
			(effects
				(font
					(size 1.27 1.27)
				)
			)
		)
		(duplicate_pad_numbers_are_jumpers no)
		(fp_line
			(start 0.787389 0.406267)
			(end -0.787389 0.406267)
			(stroke
				(width 0.1524)
				(type default)
			)
			(layer "F.SilkS")
		)
		(fp_line
			(start 0.787389 -0.406267)
			(end 0.787389 0.406267)
			(stroke
				(width 0.1524)
				(type default)
			)
			(layer "F.SilkS")
		)
		(fp_line
			(start -0.787389 0.406267)
			(end -0.787389 -0.406267)
			(stroke
				(width 0.1524)
				(type default)
			)
			(layer "F.SilkS")
		)
		(fp_line
			(start -0.787389 -0.406267)
			(end 0.787389 -0.406267)
			(stroke
				(width 0.1524)
				(type default)
			)
			(layer "F.SilkS")
		)
		(fp_line
			(start 0.679446 0.30479)
			(end 0.120515 0.30479)
			(stroke
				(width 0.1)
				(type default)
			)
			(layer "F.Fab")
		)
		(fp_line
			(start 0.120515 0.30479)
			(end 0.120335 0.279466)
			(stroke
				(width 0.1)
				(type default)
			)
			(layer "F.Fab")
		)
		(fp_line
			(start 0.120335 0.279466)
			(end -0.120695 0.279466)
			(stroke
				(width 0.1)
				(type default)
			)
			(layer "F.Fab")
		)
		(fp_line
			(start 0.679446 -0.30479)
			(end 0.679446 0.30479)
			(stroke
				(width 0.1)
				(type default)
			)
			(layer "F.Fab")
		)
		(fp_line
			(start -0.120515 0.30479)
			(end -0.679446 0.30479)
			(stroke
				(width 0.1)
				(type default)
			)
			(layer "F.Fab")
		)
		(fp_line
			(start -0.120695 0.279466)
			(end -0.120515 0.30479)
			(stroke
				(width 0.1)
				(type default)
			)
			(layer "F.Fab")
		)
		(fp_line
			(start 0.120695 -0.279466)
			(end 0.120515 -0.30479)
			(stroke
				(width 0.1)
				(type default)
			)
			(layer "F.Fab")
		)
		(fp_line
			(start 0.120515 -0.30479)
			(end 0.679446 -0.30479)
			(stroke
				(width 0.1)
				(type default)
			)
			(layer "F.Fab")
		)
		(fp_line
			(start -0.679446 0.30479)
			(end -0.679446 -0.305149)
			(stroke
				(width 0.1)
				(type default)
			)
			(layer "F.Fab")
		)
		(fp_line
			(start -0.120695 -0.279466)
			(end 0.120695 -0.279466)
			(stroke
				(width 0.1)
				(type default)
			)
			(layer "F.Fab")
		)
		(fp_line
			(start -0.120695 -0.304969)
			(end -0.120695 -0.279466)
			(stroke
				(width 0.1)
				(type default)
			)
			(layer "F.Fab")
		)
		(fp_line
			(start -0.679446 -0.305149)
			(end -0.120695 -0.304969)
			(stroke
				(width 0.1)
				(type default)
			)
			(layer "F.Fab")
		)
		(pad "1" smd circle
			(at -0.40005 0 225)
			(size 0 0)
			(layers "F.Cu" "F.Mask" "F.Paste")
			(net "PU_PEX0_PAD_TRI_L")
		)
		(pad "2" smd circle
			(at 0.40005 0 225)
			(size 0 0)
			(layers "F.Cu" "F.Mask" "F.Paste")
			(net "P1V8_PEX")
		)
	)
	(footprint ""
		(layer "F.Cu")
		(at 380.61773 -115.336574 90)
		(property "Reference" "R349"
			(at 0 0 90)
			(layer "F.SilkS")
			(hide yes)
			(effects
				(font
					(size 1.27 1.27)
				)
			)
		)
		(property "Value" ""
			(at 0 0 90)
			(layer "F.Fab")
			(effects
				(font
					(size 1.27 1.27)
				)
			)
		)
		(duplicate_pad_numbers_are_jumpers no)
		(fp_line
			(start 0.7874 -0.4064)
			(end 0.7874 0.4064)
			(stroke
				(width 0.1524)
				(type default)
			)
			(layer "F.SilkS")
		)
		(fp_line
			(start -0.7874 -0.4064)
			(end 0.7874 -0.4064)
			(stroke
				(width 0.1524)
				(type default)
			)
			(layer "F.SilkS")
		)
		(fp_line
			(start 0.7874 0.4064)
			(end -0.7874 0.4064)
			(stroke
				(width 0.1524)
				(type default)
			)
			(layer "F.SilkS")
		)
		(fp_line
			(start -0.7874 0.4064)
			(end -0.7874 -0.4064)
			(stroke
				(width 0.1524)
				(type default)
			)
			(layer "F.SilkS")
		)
		(fp_line
			(start -0.12065 -0.305054)
			(end -0.12065 -0.2794)
			(stroke
				(width 0.1)
				(type default)
			)
			(layer "F.Fab")
		)
		(fp_line
			(start -0.67945 -0.305054)
			(end -0.12065 -0.305054)
			(stroke
				(width 0.1)
				(type default)
			)
			(layer "F.Fab")
		)
		(fp_line
			(start 0.67945 -0.3048)
			(end 0.67945 0.3048)
			(stroke
				(width 0.1)
				(type default)
			)
			(layer "F.Fab")
		)
		(fp_line
			(start 0.12065 -0.3048)
			(end 0.67945 -0.3048)
			(stroke
				(width 0.1)
				(type default)
			)
			(layer "F.Fab")
		)
		(fp_line
			(start 0.12065 -0.2794)
			(end 0.12065 -0.3048)
			(stroke
				(width 0.1)
				(type default)
			)
			(layer "F.Fab")
		)
		(fp_line
			(start -0.12065 -0.2794)
			(end 0.12065 -0.2794)
			(stroke
				(width 0.1)
				(type default)
			)
			(layer "F.Fab")
		)
		(fp_line
			(start 0.120396 0.2794)
			(end -0.12065 0.2794)
			(stroke
				(width 0.1)
				(type default)
			)
			(layer "F.Fab")
		)
		(fp_line
			(start -0.12065 0.2794)
			(end -0.12065 0.3048)
			(stroke
				(width 0.1)
				(type default)
			)
			(layer "F.Fab")
		)
		(fp_line
			(start 0.67945 0.3048)
			(end 0.120396 0.3048)
			(stroke
				(width 0.1)
				(type default)
			)
			(layer "F.Fab")
		)
		(fp_line
			(start 0.120396 0.3048)
			(end 0.120396 0.2794)
			(stroke
				(width 0.1)
				(type default)
			)
			(layer "F.Fab")
		)
		(fp_line
			(start -0.12065 0.3048)
			(end -0.67945 0.3048)
			(stroke
				(width 0.1)
				(type default)
			)
			(layer "F.Fab")
		)
		(fp_line
			(start -0.67945 0.3048)
			(end -0.67945 -0.305054)
			(stroke
				(width 0.1)
				(type default)
			)
			(layer "F.Fab")
		)
		(pad "1" smd circle
			(at -0.40005 0 90)
			(size 0 0)
			(layers "F.Cu" "F.Mask" "F.Paste")
			(net "PRSNT_NIC6_R_N")
		)
		(pad "2" smd circle
			(at 0.40005 0 90)
			(size 0 0)
			(layers "F.Cu" "F.Mask" "F.Paste")
			(net "PRSNT_NIC6_N")
		)
	)
	(footprint ""
		(layer "F.Cu")
		(at 334.518 -238.633 -90)
		(property "Reference" "R1796"
			(at 0 0 270)
			(layer "F.SilkS")
			(hide yes)
			(effects
				(font
					(size 1.27 1.27)
				)
			)
		)
		(property "Value" ""
			(at 0 0 270)
			(layer "F.Fab")
			(effects
				(font
					(size 1.27 1.27)
				)
			)
		)
		(duplicate_pad_numbers_are_jumpers no)
		(fp_line
			(start -0.7874 0.4064)
			(end -0.7874 -0.4064)
			(stroke
				(width 0.1524)
				(type default)
			)
			(layer "F.SilkS")
		)
		(fp_line
			(start 0.7874 0.4064)
			(end -0.7874 0.4064)
			(stroke
				(width 0.1524)
				(type default)
			)
			(layer "F.SilkS")
		)
		(fp_line
			(start -0.7874 -0.4064)
			(end 0.7874 -0.4064)
			(stroke
				(width 0.1524)
				(type default)
			)
			(layer "F.SilkS")
		)
		(fp_line
			(start 0.7874 -0.4064)
			(end 0.7874 0.4064)
			(stroke
				(width 0.1524)
				(type default)
			)
			(layer "F.SilkS")
		)
		(fp_line
			(start -0.67945 0.3048)
			(end -0.67945 -0.305054)
			(stroke
				(width 0.1)
				(type default)
			)
			(layer "F.Fab")
		)
		(fp_line
			(start -0.12065 0.3048)
			(end -0.67945 0.3048)
			(stroke
				(width 0.1)
				(type default)
			)
			(layer "F.Fab")
		)
		(fp_line
			(start 0.120396 0.3048)
			(end 0.120396 0.2794)
			(stroke
				(width 0.1)
				(type default)
			)
			(layer "F.Fab")
		)
		(fp_line
			(start 0.67945 0.3048)
			(end 0.120396 0.3048)
			(stroke
				(width 0.1)
				(type default)
			)
			(layer "F.Fab")
		)
		(fp_line
			(start -0.12065 0.2794)
			(end -0.12065 0.3048)
			(stroke
				(width 0.1)
				(type default)
			)
			(layer "F.Fab")
		)
		(fp_line
			(start 0.120396 0.2794)
			(end -0.12065 0.2794)
			(stroke
				(width 0.1)
				(type default)
			)
			(layer "F.Fab")
		)
		(fp_line
			(start -0.12065 -0.2794)
			(end 0.12065 -0.2794)
			(stroke
				(width 0.1)
				(type default)
			)
			(layer "F.Fab")
		)
		(fp_line
			(start 0.12065 -0.2794)
			(end 0.12065 -0.3048)
			(stroke
				(width 0.1)
				(type default)
			)
			(layer "F.Fab")
		)
		(fp_line
			(start 0.12065 -0.3048)
			(end 0.67945 -0.3048)
			(stroke
				(width 0.1)
				(type default)
			)
			(layer "F.Fab")
		)
		(fp_line
			(start 0.67945 -0.3048)
			(end 0.67945 0.3048)
			(stroke
				(width 0.1)
				(type default)
			)
			(layer "F.Fab")
		)
		(fp_line
			(start -0.67945 -0.305054)
			(end -0.12065 -0.305054)
			(stroke
				(width 0.1)
				(type default)
			)
			(layer "F.Fab")
		)
		(fp_line
			(start -0.12065 -0.305054)
			(end -0.12065 -0.2794)
			(stroke
				(width 0.1)
				(type default)
			)
			(layer "F.Fab")
		)
		(pad "1" smd circle
			(at -0.40005 0 270)
			(size 0 0)
			(layers "F.Cu" "F.Mask" "F.Paste")
			(net "P3V3_AUX")
		)
		(pad "2" smd circle
			(at 0.40005 0 270)
			(size 0 0)
			(layers "F.Cu" "F.Mask" "F.Paste")
			(net "MB_SWB_PWRGD_R")
		)
	)
	(footprint ""
		(layer "F.Cu")
		(at 79.429356 -220.7006)
		(property "Reference" "J70"
			(at -1.4224 -4.562348 0)
			(unlocked yes)
			(layer "F.SilkS")
			(effects
				(font
					(size 0.7874 0.5842)
					(thickness 0.1524)
				)
				(justify left)
			)
		)
		(property "Value" ""
			(at 0 0 0)
			(layer "F.Fab")
			(effects
				(font
					(size 1.27 1.27)
				)
			)
		)
		(duplicate_pad_numbers_are_jumpers no)
		(fp_line
			(start -1.27 -3.81)
			(end 1.27 -3.81)
			(stroke
				(width 0.1524)
				(type default)
			)
			(layer "F.SilkS")
		)
		(fp_line
			(start -1.27 -0.7747)
			(end -1.27 -3.81)
			(stroke
				(width 0.1524)
				(type default)
			)
			(layer "F.SilkS")
		)
		(fp_line
			(start -1.27 3.81)
			(end -1.27 0.7747)
			(stroke
				(width 0.1524)
				(type default)
			)
			(layer "F.SilkS")
		)
		(fp_line
			(start 1.27 -3.81)
			(end 1.27 -3.3147)
			(stroke
				(width 0.1524)
				(type default)
			)
			(layer "F.SilkS")
		)
		(fp_line
			(start 1.27 -1.7653)
			(end 1.27 1.7653)
			(stroke
				(width 0.1524)
				(type default)
			)
			(layer "F.SilkS")
		)
		(fp_line
			(start 1.27 3.3147)
			(end 1.27 3.81)
			(stroke
				(width 0.1524)
				(type default)
			)
			(layer "F.SilkS")
		)
		(fp_line
			(start 1.27 3.81)
			(end -1.27 3.81)
			(stroke
				(width 0.1524)
				(type default)
			)
			(layer "F.SilkS")
		)
		(fp_poly
			(pts
				(xy 4.3942 -3.048) (xy 4.3942 -2.032) (xy 3.3782 -2.54)
			)
			(stroke
				(width 0)
				(type default)
			)
			(fill yes)
			(layer "F.SilkS")
		)
		(fp_line
			(start -1.27 -3.81)
			(end -1.27 3.81)
			(stroke
				(width 0.1)
				(type default)
			)
			(layer "F.Fab")
		)
		(fp_line
			(start -1.27 3.81)
			(end 1.27 3.81)
			(stroke
				(width 0.1)
				(type default)
			)
			(layer "F.Fab")
		)
		(fp_line
			(start 1.27 -3.81)
			(end -1.27 -3.81)
			(stroke
				(width 0.1)
				(type default)
			)
			(layer "F.Fab")
		)
		(fp_line
			(start 1.27 3.81)
			(end 1.27 -3.81)
			(stroke
				(width 0.1)
				(type default)
			)
			(layer "F.Fab")
		)
		(fp_poly
			(pts
				(xy 4.3942 -3.048) (xy 4.3942 -2.032) (xy 3.3782 -2.54)
			)
			(stroke
				(width 0)
				(type default)
			)
			(fill yes)
			(layer "F.Fab")
		)
		(fp_text user "3"
			(at 3.921252 2.54 90)
			(unlocked yes)
			(layer "F.SilkS")
			(effects
				(font
					(size 0.7874 0.5842)
					(thickness 0.1524)
				)
			)
		)
		(fp_text user "3"
			(at 3.921252 2.54 90)
			(unlocked yes)
			(layer "F.Fab")
			(effects
				(font
					(size 0.7874 0.5842)
					(thickness 0.1524)
				)
			)
		)
		(pad "1" smd rect
			(at 1.459992 -2.54 90)
			(size 1.27 3.429)
			(layers "F.Cu" "F.Mask" "F.Paste")
			(net "GND")
		)
		(pad "2" smd rect
			(at -1.459992 0 90)
			(size 1.27 3.429)
			(layers "F.Cu" "F.Mask" "F.Paste")
			(net "UART_PEX3_CLI_BUF_R1_TX")
		)
		(pad "3" smd rect
			(at 1.459992 2.54 90)
			(size 1.27 3.429)
			(layers "F.Cu" "F.Mask" "F.Paste")
			(net "UART_PEX3_CLI_R1_RX")
		)
	)
	(footprint ""
		(layer "F.Cu")
		(at 12.355322 -113.517426 90)
		(property "Reference" "R5860"
			(at 0 0 90)
			(layer "F.SilkS")
			(hide yes)
			(effects
				(font
					(size 1.27 1.27)
				)
			)
		)
		(property "Value" ""
			(at 0 0 90)
			(layer "F.Fab")
			(effects
				(font
					(size 1.27 1.27)
				)
			)
		)
		(duplicate_pad_numbers_are_jumpers no)
		(fp_line
			(start 0.7874 -0.4064)
			(end 0.7874 0.4064)
			(stroke
				(width 0.1524)
				(type default)
			)
			(layer "F.SilkS")
		)
		(fp_line
			(start -0.7874 -0.4064)
			(end 0.7874 -0.4064)
			(stroke
				(width 0.1524)
				(type default)
			)
			(layer "F.SilkS")
		)
		(fp_line
			(start 0.7874 0.4064)
			(end -0.7874 0.4064)
			(stroke
				(width 0.1524)
				(type default)
			)
			(layer "F.SilkS")
		)
		(fp_line
			(start -0.7874 0.4064)
			(end -0.7874 -0.4064)
			(stroke
				(width 0.1524)
				(type default)
			)
			(layer "F.SilkS")
		)
		(fp_line
			(start -0.12065 -0.305054)
			(end -0.12065 -0.2794)
			(stroke
				(width 0.1)
				(type default)
			)
			(layer "F.Fab")
		)
		(fp_line
			(start -0.67945 -0.305054)
			(end -0.12065 -0.305054)
			(stroke
				(width 0.1)
				(type default)
			)
			(layer "F.Fab")
		)
		(fp_line
			(start 0.67945 -0.3048)
			(end 0.67945 0.3048)
			(stroke
				(width 0.1)
				(type default)
			)
			(layer "F.Fab")
		)
		(fp_line
			(start 0.12065 -0.3048)
			(end 0.67945 -0.3048)
			(stroke
				(width 0.1)
				(type default)
			)
			(layer "F.Fab")
		)
		(fp_line
			(start 0.12065 -0.2794)
			(end 0.12065 -0.3048)
			(stroke
				(width 0.1)
				(type default)
			)
			(layer "F.Fab")
		)
		(fp_line
			(start -0.12065 -0.2794)
			(end 0.12065 -0.2794)
			(stroke
				(width 0.1)
				(type default)
			)
			(layer "F.Fab")
		)
		(fp_line
			(start 0.120396 0.2794)
			(end -0.12065 0.2794)
			(stroke
				(width 0.1)
				(type default)
			)
			(layer "F.Fab")
		)
		(fp_line
			(start -0.12065 0.2794)
			(end -0.12065 0.3048)
			(stroke
				(width 0.1)
				(type default)
			)
			(layer "F.Fab")
		)
		(fp_line
			(start 0.67945 0.3048)
			(end 0.120396 0.3048)
			(stroke
				(width 0.1)
				(type default)
			)
			(layer "F.Fab")
		)
		(fp_line
			(start 0.120396 0.3048)
			(end 0.120396 0.2794)
			(stroke
				(width 0.1)
				(type default)
			)
			(layer "F.Fab")
		)
		(fp_line
			(start -0.12065 0.3048)
			(end -0.67945 0.3048)
			(stroke
				(width 0.1)
				(type default)
			)
			(layer "F.Fab")
		)
		(fp_line
			(start -0.67945 0.3048)
			(end -0.67945 -0.305054)
			(stroke
				(width 0.1)
				(type default)
			)
			(layer "F.Fab")
		)
		(pad "1" smd circle
			(at -0.40005 0 90)
			(size 0 0)
			(layers "F.Cu" "F.Mask" "F.Paste")
			(net "P5V_AUX")
		)
		(pad "2" smd circle
			(at 0.40005 0 90)
			(size 0 0)
			(layers "F.Cu" "F.Mask" "F.Paste")
			(net "P3V3_NIC0_PG_G2")
		)
	)
)
